FILE_TYPE = CONNECTIVITY;
{Allegro Design Entry HDL 16.6-p007 (v16-6-112F) 10/10/2012}
"PAGE_NUMBER" = 208;
0"NC";
1"GND\g";
2"GND\g";
3"PVCCIN_CPU1\g";
4"GND\g";
5"GND\g";
6"PVCCIN_CPU1\g";
7"GND\g";
8"VR_FET_SW_P12V_STBY_PVCCIN_CPU1\g";
9"GND\g";
10"VR_FET_SW_P12V_STBY_PVCCIN_CPU1\g";
11"GND\g";
12"P5V_STBY\g";
13"P5V_STBY\g";
14"GND\g";
15"GND\g";
16"GND\g";
17"PVCCIN_CPU1\g";
18"GND\g";
19"GND\g";
20"GND\g";
21"GND\g";
22"GND\g";
23"A_TSENSE_PVCCIN_CPU1";
24"VR_PVCCIN_CPU1_PHASE3"VOLTAGE"5";
25"VR_PVCCIN_CPU1_PH4_PHASE"VOLTAGE"5";
26"VR_PVCCIN_CPU1_PH4_OCSET";
27"ISENSE_PVCCIN_CPU1_PH4_IMON";
28"VR_PVCCIN_CPU1_PH4_VCIN"VOLTAGE"5";
29"VR_PVCCIN_CPU1_PHASE4"VOLTAGE"5";
30"TP_PVCCIN_CPU1_PH4_GL_1";
31"A_TSENSE_PVCCIN_CPU1";
32"UN$208$3D01R5F-GP$I94$2";
33"UN$208$3D01R5F-GP$I86$2";
34"VR_PVCCIN_CPU1_AIREF4";
35"NC_PVCCIN_CPU1_PH3_P31";
36"VR_PVCCIN_CPU1_PH4_BOOT";
37"VR_PVCCIN_CPU1_PH4_BOOT_R";
38"VR_PVCCIN_CPU1_PWM4";
39"TP_PVCCIN_CPU1_PH4_GL_0";
40"VR_PVCCIN_CPU1_PWM3";
41"VR_PVCCIN_CPU1_PH3_BOOT";
42"VR_PVCCIN_CPU1_PH3_PHASE";
43"VR_PVCCIN_CPU1_PH3_BOOT_R";
44"VR_PVCCIN_CPU1_AIREF3";
45"ISENSE_PVCCIN_CPU1_PH3_IMON";
46"VR_PVCCIN_CPU1_PH3_OCSET";
47"VR_PVCCIN_CPU1_PH3_VCIN"VOLTAGE"5";
48"TP_PVCCIN_CPU1_PH3_GL_0";
49"TP_PVCCIN_CPU1_PH3_GL_1";
50"NC_PVCCIN_CPU1_PH4_P31";
%"GND"
"1","(-400,3050)","0","mstr_symbols","I10";
;
ROOM"PVCCIN_CPU1_PWR_VR"
BOM_COST"PROC_VRD_VCCIN_CPU0"
SIZE"1B"
CDS_LIB"mstr_symbols"
VOLTAGE"0"
BODY_TYPE"PLUMBING"
HDL_POWER"GND";
"A\NAC"1;
%"INDUCTOR"
"1","(-1475,3625)","0","mstr_discrete","I11";
;
CDS_LIB"mstr_discrete"
ROOM"PVCCIN_CPU1_PWR_VR"
CDS_LOCATION"L1D2"
$SEC"1"
CDS_SEC"1"
VALUE"0.12UH"
PACK_TYPE"SM"
LOCATION"L1D2"
PART_NUMBER"D92183-034"
MATERIAL"IND";
"INA\NAC"
$PN"1"24;
"INB\NAC"
$PN"2"17;
%"CAPP"
"1","(-1450,2625)","0","mstr_discrete","I12";
;
CDS_SEC"1"
CDS_LIB"mstr_discrete"
ROOM"PVCCIN_CPU1_DECAP_VR"
CDS_LOCATION"C9P8"
VOLTAGE"2.5V"
BOM_COST"PROC_VRD_VCCIN_CPU0"
SEC"1"
SEC_TYPE"3018"
LOCATION"C9P8"
MATERIAL"ALUM"
PART_NUMBER"699013-049"
PACK_TYPE"3018"
VALUE"470UF"
TOLERANCE"20%";
"B"
$PN"2"2;
"A"
$PN"1"6;
%"GND"
"1","(-1000,2275)","0","mstr_symbols","I13";
;
ROOM"PVCCIN_CPU1_DECAP_VR"
BOM_COST"PROC_VRD_VCCIN_CPU0"
SIZE"1B"
CDS_LIB"mstr_symbols"
VOLTAGE"0"
BODY_TYPE"PLUMBING"
HDL_POWER"GND";
"A\NAC"2;
%"CAPP"
"1","(-1925,2625)","0","mstr_discrete","I14";
;
CDS_SEC"1"
CDS_LIB"mstr_discrete"
ROOM"PVCCIN_CPU1_DECAP_VR"
CDS_LOCATION"C9P5"
VOLTAGE"2.5V"
BOM_COST"PROC_VRD_VCCIN_CPU0"
SEC"1"
SEC_TYPE"3018"
VALUE"470UF"
LOCATION"C9P5"
MATERIAL"ALUM"
TOLERANCE"20%"
PACK_TYPE"3018"
PART_NUMBER"699013-049";
"B"
$PN"2"2;
"A"
$PN"1"6;
%"PVCCIN_CPU1"
"1","(-350,1125)","0","mstr_symbols","I18";
;
CDS_LIB"mstr_symbols"
VOLTAGE"2.0V"
BODY_TYPE"PLUMBING"
HDL_POWER"PVCCIN_CPU1";
"G\NAC"3;
%"INDUCTOR"
"1","(-1325,1025)","0","mstr_discrete","I20";
;
CDS_SEC"1"
$SEC"1"
CDS_LOCATION"L1D1"
ROOM"PVCCIN_CPU1_PWR_VR"
CDS_LIB"mstr_discrete"
MATERIAL"IND"
PART_NUMBER"D92183-034"
PACK_TYPE"SM"
LOCATION"L1D1"
VALUE"0.12UH";
"INA\NAC"
$PN"1"29;
"INB\NAC"
$PN"2"3;
%"GND"
"1","(-350,450)","0","mstr_symbols","I21";
;
ROOM"PVCCIN_CPU1_PWR_VR"
BOM_COST"PROC_VRD_VCCIN_CPU0"
CDS_LIB"mstr_symbols"
SIZE"1B"
VOLTAGE"0"
BODY_TYPE"PLUMBING"
HDL_POWER"GND";
"A\NAC"4;
%"CAP_A"
"1","(-700,800)","0","dev_discrete","I22";
;
CDS_LIB"dev_discrete"
ROOM"PVCCIN_CPU1_PWR_VR"
CDS_SEC"1"
CDS_LOCATION"C1D3"
BOM_COST"PROC_VRD_VCCIN_CPU0"
SEC"1"
SEC_TYPE"0603V"
PART_NUMBER"E15431-004"
PACK_TYPE"0603V"
MATERIAL"X6S"
VOLTAGE"4V"
TOLERANCE"20%"
VALUE"22.0UF"
LOCATION"C1D3";
"B"
$PN"2"4;
"A"
$PN"1"3;
%"GND"
"1","(-2600,3175)","0","mstr_symbols","I23";
;
ROOM"PVCCIN_CPU1_PWR_VR"
BOM_COST"PROC_VRD_VCCIN_CPU0"
CDS_LIB"mstr_symbols"
VOLTAGE"0"
SIZE"1B"
BODY_TYPE"PLUMBING"
HDL_POWER"GND";
"A\NAC"5;
%"CAPP"
"1","(-2375,2600)","0","mstr_discrete","I24";
;
CDS_SEC"1"
VOLTAGE"2.5V"
CDS_LIB"mstr_discrete"
ROOM"PVCCIN_CPU1_DECAP_VR"
CDS_LOCATION"C9N24"
BOM_COST"PROC_VRD_VCCIN_CPU0"
SEC"1"
SEC_TYPE"3018"
VALUE"470UF"
PACK_TYPE"3018"
MATERIAL"ALUM"
TOLERANCE"20%"
PART_NUMBER"699013-049"
LOCATION"C9N24";
"B"
$PN"2"2;
"A"
$PN"1"6;
%"CAPP"
"1","(-2825,2625)","0","mstr_discrete","I25";
;
CDS_SEC"1"
CDS_LIB"mstr_discrete"
VOLTAGE"2.5V"
CDS_LOCATION"C9R9"
ROOM"PVCCIN_CPU1_DECAP_VR"
BOM_COST"PROC_VRD_VCCIN_CPU0"
SEC_TYPE"3018"
SEC"1"
PACK_TYPE"3018"
PART_NUMBER"699013-049"
MATERIAL"ALUM"
VALUE"470UF"
LOCATION"C9R9"
TOLERANCE"20%";
"B"
$PN"2"2;
"A"
$PN"1"6;
%"CAPP"
"1","(-3275,2625)","0","mstr_discrete","I26";
;
CDS_SEC"1"
CDS_LIB"mstr_discrete"
VOLTAGE"2.5V"
ROOM"PVCCIN_CPU1_DECAP_VR"
CDS_LOCATION"C9R3"
BOM_COST"PROC_VRD_VCCIN_CPU0"
SEC"1"
SEC_TYPE"3018"
MATERIAL"ALUM"
TOLERANCE"20%"
VALUE"470UF"
LOCATION"C9R3"
PART_NUMBER"699013-049"
PACK_TYPE"3018";
"B"
$PN"2"2;
"A"
$PN"1"6;
%"IR354XX"
"1","(-3300,3875)","0","mstr_discrete","I27";
;
CDS_SEC"1"
ROOM"PVCCIN_CPU1_PWR_VR"
CDS_LIB"mstr_discrete"
PACK_TYPE"SM"
CDS_LOCATION"EU1D3"
SEC_TYPE"SM"
SEC"1"
PART_NUMBER"H73688-001"
MATERIAL"IC"
LOCATION"EU1D3"
VALUE"IR35411";
"TOUT_FLT"
$PN"36"23;
"NC"
$PN"31"35;
"OCSET"
$PN"37"46;
"IOUT"
$PN"38"45;
"SW"
$PN"10"24;
"BOOST"
$PN"33"43;
"REFIN"
$PN"39"44;
"PWM"
$PN"34"40;
"PHASE"
$PN"32"42;
"VIN<0>"
$PN"25"8;
"VCC"
$PN"3"47;
"VIN<1>"
$PN"30"8;
"EN"
$PN"35"12;
"VDRV"
$PN"4"12;
"VOS"
$PN"1"17;
"LGND"
$PN"2"5;
"PGND<1>"
$PN"7"5;
"PGND<2>"
$PN"40"5;
"PGND<0>"
$PN"5"5;
"GL<0>"
$PN"6"48;
"GL<1>"
$PN"41"49;
%"CAPP"
"1","(-3725,2625)","0","mstr_discrete","I28";
;
CDS_SEC"1"
CDS_LIB"mstr_discrete"
ROOM"PVCCIN_CPU1_DECAP_VR"
CDS_LOCATION"C9P23"
VOLTAGE"2.5V"
BOM_COST"PROC_VRD_VCCIN_CPU0"
SEC"1"
SEC_TYPE"3018"
LOCATION"C9P23"
VALUE"470UF"
TOLERANCE"20%"
MATERIAL"ALUM"
PACK_TYPE"3018"
PART_NUMBER"699013-049";
"B"
$PN"2"2;
"A"
$PN"1"6;
%"PVCCIN_CPU1"
"1","(-4250,2900)","0","mstr_symbols","I29";
;
HDL_POWER"PVCCIN_CPU1"
BODY_TYPE"PLUMBING"
VOLTAGE"2.0V"
CDS_LIB"mstr_symbols";
"G\NAC"6;
%"CAPP"
"1","(-4150,2625)","0","mstr_discrete","I30";
;
CDS_SEC"1"
CDS_LIB"mstr_discrete"
ROOM"PVCCIN_CPU1_DECAP_VR"
CDS_LOCATION"C9P18"
BOM_COST"PROC_VRD_VCCIN_CPU0"
SEC"1"
SEC_TYPE"3018"
VALUE"470UF"
LOCATION"C9P18"
MATERIAL"ALUM"
PACK_TYPE"3018"
PART_NUMBER"699013-049"
TOLERANCE"20%"
VOLTAGE"2.5V";
"B"
$PN"2"2;
"A"
$PN"1"6;
%"GND"
"1","(-2575,600)","0","mstr_symbols","I33";
;
ROOM"PVCCIN_CPU1_PWR_VR"
BOM_COST"PROC_VRD_VCCIN_CPU0"
CDS_LIB"mstr_symbols"
VOLTAGE"0"
SIZE"1B"
BODY_TYPE"PLUMBING"
HDL_POWER"GND";
"A\NAC"7;
%"RES"
"1","(-5275,4700)","0","mstr_discrete","I36";
;
CDS_SEC"1"
SEC_TYPE"0402"
SEC"1"
ROOM"PVCCIN_CPU1_PWR_VR"
CDS_LOCATION"R9P22"
CDS_LIB"mstr_discrete"
PART_NUMBER"G21796-090"
PACK_TYPE"0402"
MATERIAL"CHIP"
LOCATION"R9P22"
TOLERANCE"1%"
VALUE"1.0"
WATTAGE"1/16W";
"B"
$PN"2"12;
"A"
$PN"1"47;
%"VCC_CORE"
"1","(-7425,4525)","0","mstr_symbols","I37";
;
CDS_LIB"mstr_symbols"
HDL_POWER"VR_FET_SW_P12V_STBY_PVCCIN_CPU1";
"A"8;
%"CAP"
"1","(-4850,4200)","0","mstr_discrete","I38";
;
CDS_SEC"1"
CDS_LIB"mstr_discrete"
CDS_LOCATION"C1D16"
ROOM"PVCCIN_CPU1_PWR_VR"
SEC_TYPE"0402"
SEC"1"
LOCATION"C1D16"
VALUE"0.22UF"
TOLERANCE"10%"
VOLTAGE"16V"
MATERIAL"X7R"
PACK_TYPE"0402"
PART_NUMBER"A36096-155";
"A"
$PN"1"12;
"B"
$PN"2"9;
%"CAP_A"
"1","(-5000,4200)","2","dev_discrete","I39";
;
CDS_LOCATION"C1D15"
CDS_LIB"dev_discrete"
CDS_SEC"1"
ROOM"PVCCIN_CPU1_PWR_VR"
SEC"1"
SEC_TYPE"0402V"
MATERIAL"X6S"
VOLTAGE"6.3V"
TOLERANCE"10%"
VALUE"1.0UF"
LOCATION"C1D15"
PACK_TYPE"0402V"
PART_NUMBER"D97712-004";
"B"
$PN"2"9;
"A"
$PN"1"12;
%"CAP"
"1","(-5975,3575)","2","mstr_discrete","I40";
;
CDS_SEC"1"
ROOM"PVCCIN_CPU1_PWR_VR"
NO_XNET_CONNECTION"1"
CDS_LOCATION"C1D20"
SEC"1"
SPOF"TRUE"
SEC_TYPE"0402"
CDS_LIB"mstr_discrete"
MATERIAL"X7R"
PACK_TYPE"0402"
PART_NUMBER"A36096-104"
VALUE"0.220UF"
LOCATION"C1D20"
VOLTAGE"16V"
TOLERANCE"10%";
"A"
$PN"1"41;
"B"
$PN"2"42;
%"CAP"
"1","(-5575,4150)","0","mstr_discrete","I43";
;
CDS_SEC"1"
CDS_LOCATION"C1D17"
CDS_LIB"mstr_discrete"
ROOM"PVCCIN_CPU1_PWR_VR"
SEC"1"
SEC_TYPE"0402"
PACK_TYPE"0402"
MATERIAL"X6S"
LOCATION"C1D17"
TOLERANCE"10%"
VOLTAGE"16V"
VALUE"1.0UF"
PART_NUMBER"D97712-011";
"A"
$PN"1"47;
"B"
$PN"2"9;
%"CAP_A"
"1","(-5875,4150)","0","dev_discrete","I44";
;
CDS_LOCATION"C1D28"
CDS_LIB"dev_discrete"
CDS_SEC"1"
ROOM"PVCCIN_CPU1_PWR_VR"
SEC_TYPE"0402V"
SEC"1"
PART_NUMBER"A36096-030"
PACK_TYPE"0402V"
MATERIAL"X7R"
TOLERANCE"10%"
LOCATION"C1D28"
VALUE"0.1UF"
VOLTAGE"16V";
"B"
$PN"2"9;
"A"
$PN"1"8;
%"CAP"
"1","(-6250,4150)","0","mstr_discrete","I45";
;
CDS_SEC"1"
CDS_LIB"mstr_discrete"
CDS_LOCATION"C1D23"
SEC_TYPE"0402"
SEC"1"
ROOM"PVCCIN_CPU1_PWR_VR"
MATERIAL"X6S"
PACK_TYPE"0402"
VOLTAGE"16V"
TOLERANCE"10%"
VALUE"1.0UF"
LOCATION"C1D23"
PART_NUMBER"D97712-011";
"A"
$PN"1"8;
"B"
$PN"2"9;
%"CAP"
"1","(-4900,1575)","0","mstr_discrete","I46";
;
CDS_SEC"1"
CDS_LIB"mstr_discrete"
ROOM"PVCCIN_CPU1_PWR_VR"
CDS_LOCATION"C1D6"
SEC"1"
SEC_TYPE"0402"
PART_NUMBER"A36096-155"
TOLERANCE"10%"
VOLTAGE"16V"
VALUE"0.22UF"
LOCATION"C1D6"
PACK_TYPE"0402"
MATERIAL"X7R";
"A"
$PN"1"13;
"B"
$PN"2"11;
%"CAP_A"
"1","(-5075,1575)","2","dev_discrete","I47";
;
ROOM"PVCCIN_CPU1_PWR_VR"
SEC"1"
SEC_TYPE"0402V"
CDS_SEC"1"
CDS_LOCATION"C1D5"
CDS_LIB"dev_discrete"
MATERIAL"X6S"
PACK_TYPE"0402V"
TOLERANCE"10%"
VOLTAGE"6.3V"
LOCATION"C1D5"
VALUE"1.0UF"
PART_NUMBER"D97712-004";
"B"
$PN"2"11;
"A"
$PN"1"13;
%"CAP"
"1","(-5975,900)","2","mstr_discrete","I48";
;
CDS_SEC"1"
CDS_LIB"mstr_discrete"
ROOM"PVCCIN_CPU1_PWR_VR"
NO_XNET_CONNECTION"1"
CDS_LOCATION"C1D10"
SEC"1"
SEC_TYPE"0402"
SPOF"TRUE"
VOLTAGE"16V"
PART_NUMBER"A36096-104"
VALUE"0.220UF"
PACK_TYPE"0402"
LOCATION"C1D10"
MATERIAL"X7R"
TOLERANCE"10%";
"A"
$PN"1"36;
"B"
$PN"2"25;
%"RES"
"1","(-5450,2025)","0","mstr_discrete","I49";
;
CDS_SEC"1"
ROOM"PVCCIN_CPU1_PWR_VR"
CDS_LOCATION"R9P8"
SEC"1"
SEC_TYPE"0402"
CDS_LIB"mstr_discrete"
TOLERANCE"1%"
WATTAGE"1/16W"
VALUE"1.0"
LOCATION"R9P8"
PART_NUMBER"G21796-090"
PACK_TYPE"0402"
MATERIAL"CHIP";
"B"
$PN"2"13;
"A"
$PN"1"28;
%"CAP"
"1","(-5700,1575)","0","mstr_discrete","I50";
;
CDS_SEC"1"
CDS_LIB"mstr_discrete"
CDS_LOCATION"C1D7"
ROOM"PVCCIN_CPU1_PWR_VR"
SEC_TYPE"0402"
SEC"1"
MATERIAL"X6S"
PACK_TYPE"0402"
VALUE"1.0UF"
PART_NUMBER"D97712-011"
LOCATION"C1D7"
VOLTAGE"16V"
TOLERANCE"10%";
"A"
$PN"1"28;
"B"
$PN"2"11;
%"CAP_A"
"1","(-6025,1450)","0","dev_discrete","I51";
;
CDS_LIB"dev_discrete"
ROOM"PVCCIN_CPU1_PWR_VR"
CDS_LOCATION"C1D13"
CDS_SEC"1"
SEC_TYPE"0402V"
SEC"1"
PART_NUMBER"A36096-030"
VALUE"0.1UF"
TOLERANCE"10%"
PACK_TYPE"0402V"
VOLTAGE"16V"
MATERIAL"X7R"
LOCATION"C1D13";
"B"
$PN"2"11;
"A"
$PN"1"10;
%"CAP"
"1","(-6350,1500)","0","mstr_discrete","I52";
;
CDS_SEC"1"
CDS_LIB"mstr_discrete"
ROOM"PVCCIN_CPU1_PWR_VR"
CDS_LOCATION"C1D12"
SEC"1"
SEC_TYPE"0402"
MATERIAL"X6S"
VOLTAGE"16V"
PACK_TYPE"0402"
TOLERANCE"10%"
VALUE"1.0UF"
LOCATION"C1D12"
PART_NUMBER"D97712-011";
"A"
$PN"1"10;
"B"
$PN"2"11;
%"CAP"
"1","(-6625,4150)","0","mstr_discrete","I53";
;
CDS_SEC"1"
CDS_LIB"mstr_discrete"
CDS_LOCATION"C9P4"
SEC_TYPE"0805"
SEC"1"
ROOM"PVCCIN_CPU1_PWR_VR"
MATERIAL"X6S"
PACK_TYPE"0805"
PART_NUMBER"C95333-007"
LOCATION"C9P4"
VALUE"10UF"
TOLERANCE"10%"
VOLTAGE"16V";
"A"
$PN"1"8;
"B"
$PN"2"9;
%"CAP"
"1","(-7000,4150)","0","mstr_discrete","I54";
;
CDS_SEC"1"
CDS_LIB"mstr_discrete"
CDS_LOCATION"C9P7"
SEC_TYPE"0805"
SEC"1"
ROOM"PVCCIN_CPU1_PWR_VR"
MATERIAL"X6S"
PACK_TYPE"0805"
PART_NUMBER"C95333-007"
VOLTAGE"16V"
TOLERANCE"10%"
VALUE"10UF"
LOCATION"C9P7";
"A"
$PN"1"8;
"B"
$PN"2"9;
%"CAP"
"1","(-7375,4150)","0","mstr_discrete","I55";
;
CDS_SEC"1"
CDS_LIB"mstr_discrete"
CDS_LOCATION"C9P9"
ROOM"PVCCIN_CPU1_PWR_VR"
SEC"1"
SEC_TYPE"0805"
PACK_TYPE"0805"
MATERIAL"X6S"
PART_NUMBER"C95333-007"
VALUE"10UF"
LOCATION"C9P9"
VOLTAGE"16V"
TOLERANCE"10%";
"A"
$PN"1"8;
"B"
$PN"2"9;
%"GND"
"1","(-7425,3775)","0","mstr_symbols","I57";
;
ROOM"PVCCIN_CPU1_PWR_VR"
BOM_COST"PROC_VRD_VCCIN_CPU0"
VOLTAGE"0"
CDS_LIB"mstr_symbols"
SIZE"1B"
BODY_TYPE"PLUMBING"
HDL_POWER"GND";
"A\NAC"9;
%"CAP"
"1","(-6725,1475)","0","mstr_discrete","I58";
;
CDS_SEC"1"
CDS_LOCATION"C9P24"
CDS_LIB"mstr_discrete"
SEC_TYPE"0805"
SEC"1"
ROOM"PVCCIN_CPU1_PWR_VR"
MATERIAL"X6S"
VOLTAGE"16V"
PACK_TYPE"0805"
TOLERANCE"10%"
VALUE"10UF"
LOCATION"C9P24"
PART_NUMBER"C95333-007";
"A"
$PN"1"10;
"B"
$PN"2"11;
%"CAP"
"1","(-7075,1475)","0","mstr_discrete","I59";
;
CDS_SEC"1"
CDS_LIB"mstr_discrete"
SEC_TYPE"0805"
SEC"1"
CDS_LOCATION"C9P1"
ROOM"PVCCIN_CPU1_PWR_VR"
MATERIAL"X6S"
VOLTAGE"16V"
TOLERANCE"10%"
PACK_TYPE"0805"
PART_NUMBER"C95333-007"
VALUE"10UF"
LOCATION"C9P1";
"A"
$PN"1"10;
"B"
$PN"2"11;
%"CAP"
"1","(-7375,1500)","0","mstr_discrete","I60";
;
CDS_SEC"1"
CDS_LIB"mstr_discrete"
SEC_TYPE"0805"
SEC"1"
ROOM"PVCCIN_CPU1_PWR_VR"
CDS_LOCATION"C9P2"
MATERIAL"X6S"
VOLTAGE"16V"
PACK_TYPE"0805"
TOLERANCE"10%"
LOCATION"C9P2"
VALUE"10UF"
PART_NUMBER"C95333-007";
"A"
$PN"1"10;
"B"
$PN"2"11;
%"VCC_CORE"
"1","(-7375,1950)","0","mstr_symbols","I62";
;
CDS_LIB"mstr_symbols"
HDL_POWER"VR_FET_SW_P12V_STBY_PVCCIN_CPU1";
"A"10;
%"GND"
"1","(-7375,950)","0","mstr_symbols","I63";
;
SIZE"1B"
CDS_LIB"mstr_symbols"
VOLTAGE"0"
ROOM"PVCCIN_CPU1_PWR_VR"
BOM_COST"PROC_VRD_VCCIN_CPU0"
BODY_TYPE"PLUMBING"
HDL_POWER"GND";
"A\NAC"11;
%"P5V_STBY"
"1","(-4925,4850)","0","mstr_symbols","I64";
;
VOLTAGE"5.0V"
CDS_LIB"mstr_symbols"
SIZE"1B"
BODY_TYPE"PLUMBING"
HDL_POWER"P5V_STBY";
"G\NAC"12;
%"P5V_STBY"
"1","(-5000,2150)","0","mstr_symbols","I65";
;
CDS_LIB"mstr_symbols"
SIZE"1B"
VOLTAGE"5.0V"
BODY_TYPE"PLUMBING"
HDL_POWER"P5V_STBY";
"G\NAC"13;
%"CAP_A"
"1","(-400,3400)","0","dev_discrete","I66";
;
CDS_LIB"dev_discrete"
CDS_LOCATION"C9P10"
CDS_SEC"1"
SEC"1"
SEC_TYPE"0603V"
LOCATION"C9P10"
TOLERANCE"20%"
MATERIAL"X6S"
PART_NUMBER"E15431-004"
VALUE"22.0UF"
PACK_TYPE"0603V"
VOLTAGE"4V";
"B"
$PN"2"1;
"A"
$PN"1"17;
%"CAP_A"
"1","(-350,800)","0","dev_discrete","I67";
;
CDS_LIB"dev_discrete"
CDS_LOCATION"C9R2"
CDS_SEC"1"
SEC"1"
SEC_TYPE"0603V"
LOCATION"C9R2"
TOLERANCE"20%"
VOLTAGE"4V"
PACK_TYPE"0603V"
PART_NUMBER"E15431-004"
MATERIAL"X6S"
VALUE"22.0UF";
"B"
$PN"2"4;
"A"
$PN"1"3;
%"RES"
"2","(-1000,2575)","0","mstr_discrete","I7";
;
CDS_SEC"1"
CDS_LIB"mstr_discrete"
ROOM"PVCCIN_CPU1_DECAP_VR"
CDS_LOCATION"R1E3"
BOM_COST"PROC_VRD_VCCIN_CPU0"
SEC"1"
SEC_TYPE"0603"
PACK_TYPE"0603"
TOLERANCE"1%"
VALUE"100.0"
LOCATION"R1E3"
PART_NUMBER"G22026-038"
MATERIAL"CHIP"
WATTAGE"1/10W";
"A"
$PN"1"6;
"B"
$PN"2"2;
%"IR354XX"
"1","(-3250,1275)","0","mstr_discrete","I71";
;
CDS_SEC"1"
CDS_LOCATION"EU1D1"
CDS_LIB"mstr_discrete"
ROOM"PVCCIN_CPU1_PWR_VR"
PACK_TYPE"SM"
SEC"1"
SEC_TYPE"SM"
LOCATION"EU1D1"
VALUE"IR35411"
MATERIAL"IC"
PART_NUMBER"H73688-001";
"TOUT_FLT"
$PN"36"31;
"NC"
$PN"31"50;
"OCSET"
$PN"37"26;
"IOUT"
$PN"38"27;
"SW"
$PN"10"29;
"BOOST"
$PN"33"37;
"REFIN"
$PN"39"34;
"PWM"
$PN"34"38;
"PHASE"
$PN"32"25;
"VIN<0>"
$PN"25"10;
"VCC"
$PN"3"28;
"VIN<1>"
$PN"30"10;
"EN"
$PN"35"13;
"VDRV"
$PN"4"13;
"VOS"
$PN"1"3;
"LGND"
$PN"2"7;
"PGND<1>"
$PN"7"7;
"PGND<2>"
$PN"40"7;
"PGND<0>"
$PN"5"7;
"GL<0>"
$PN"6"39;
"GL<1>"
$PN"41"30;
%"RES"
"2","(-625,1450)","0","mstr_discrete","I75";
;
CDS_LOCATION"R1D54"
CDS_LIB"mstr_discrete"
CDS_SEC"1"
$SEC"1"
PACK_TYPE"0402"
MATERIAL"EMPTY"
VALUE"68.1K"
LOCATION"R1D54"
WATTAGE"1/16W"
TOLERANCE"1%"
PART_NUMBER"G21796-187";
"A"
$PN"1"26;
"B"
$PN"2"15;
%"RES"
"2","(-700,4075)","0","mstr_discrete","I76";
;
CDS_LOCATION"R1D55"
CDS_LIB"mstr_discrete"
$SEC"1"
CDS_SEC"1"
WATTAGE"1/16W"
PACK_TYPE"0402"
MATERIAL"EMPTY"
PART_NUMBER"G21796-187"
TOLERANCE"1%"
VALUE"68.1K"
LOCATION"R1D55";
"A"
$PN"1"46;
"B"
$PN"2"14;
%"GND"
"1","(-700,3825)","0","mstr_symbols","I77";
;
ROOM"PVCCIN_CPU1_PWR_VR"
BOM_COST"PROC_VRD_VCCIN_CPU0"
SIZE"1B"
CDS_LIB"mstr_symbols"
VOLTAGE"0"
BODY_TYPE"PLUMBING"
HDL_POWER"GND";
"A\NAC"14;
%"GND"
"1","(-625,1225)","0","mstr_symbols","I78";
;
ROOM"PVCCIN_CPU1_PWR_VR"
BOM_COST"PROC_VRD_VCCIN_CPU0"
CDS_LIB"mstr_symbols"
SIZE"1B"
VOLTAGE"0"
BODY_TYPE"PLUMBING"
HDL_POWER"GND";
"A\NAC"15;
%"GND"
"1","(-3975,3125)","0","mstr_symbols","I79";
;
CDS_LIB"mstr_symbols"
VOLTAGE"0"
SIZE"1B"
BOM_COST"PROC_VRD_VCCIN_CPU0"
ROOM"PVCCIN_CPU0_PWR_VR"
BODY_TYPE"PLUMBING"
HDL_POWER"GND";
"A\NAC"16;
%"PVCCIN_CPU1"
"1","(-400,3700)","0","mstr_symbols","I8";
;
VOLTAGE"2.0V"
CDS_LIB"mstr_symbols"
BODY_TYPE"PLUMBING"
HDL_POWER"PVCCIN_CPU1";
"G\NAC"17;
%"CAP_A"
"1","(-3975,3375)","0","dev_discrete","I80";
;
CDS_SEC"1"
$SEC"1"
CDS_LOCATION"CT16"
CDS_LIB"dev_discrete"
ROOM"PVCCIN_CPU0_PWR_VR"
STATUS"NOPOP"
PACK_TYPE"0402V"
PART_NUMBER"A36096-030"
VALUE"0.1UF"
LOCATION"CT16"
VOLTAGE"16V"
TOLERANCE"10%"
MATERIAL"X7R";
"B"
$PN"2"16;
"A"
$PN"1"44;
%"CAP"
"1","(-2050,3900)","0","mstr_discrete","I82";
;
CDS_SEC"1"
$SEC"1"
CDS_LOCATION"CTI7"
CDS_LIB"mstr_discrete"
ROOM"VDDQ_KLM_PWR_VR"
LOCATION"CTI7"
VALUE"1000PF"
TOLERANCE"10%"
MATERIAL"X7R"
PART_NUMBER"A36096-046"
PACK_TYPE"0402LF"
VOLTAGE"50V"
STATUS"NOPOP";
"A"
$PN"1"23;
"B"
$PN"2"18;
%"GND"
"1","(-2050,3700)","0","mstr_symbols","I83";
;
CDS_LIB"mstr_symbols"
ROOM"VDDQ_KLM_PWR_VR"
VOLTAGE"0"
SIZE"1B"
BODY_TYPE"PLUMBING"
HDL_POWER"GND";
"A\NAC"18;
%"SC2K2P50V3KX-GP"
"1","(-2000,3500)","0","w_hdl","I84";
;
CDS_SEC"1"
$SEC"1"
CDS_LOCATION"CT18"
PART_NUMBER"78.22224.2BL"
PACK_TYPE"SMD-BCG6"
CDS_LMAN_SYM_OUTLINE"-50,25,50,-25"
CDS_LIB"w_hdl"
VALUE"SC2K2P50V3KX-GP"
STATUS"NOPOP"
LOCATION"CT18";
"2"
$PN"2"33;
"1"
$PN"1"24;
%"GND"
"1","(-2000,3000)","0","mstr_symbols","I85";
;
CDS_LIB"mstr_symbols"
ROOM"PVCCIN_CPU0_PWR_VR"
BOM_COST"PROC_VRD_VCCIN_CPU0"
VOLTAGE"0"
SIZE"1B"
BODY_TYPE"PLUMBING"
HDL_POWER"GND";
"A\NAC"19;
%"3D01R5F-GP"
"1","(-2000,3200)","4","w_hdl","I86";
;
CDS_SEC"1"
$SEC"1"
CDS_LOCATION"RT12"
CDS_LMAN_SYM_OUTLINE"-50,75,50,-75"
CDS_LIB"w_hdl"
PART_NUMBER"64.3R015.16L"
PACK_TYPE"SMD-RG5"
LOCATION"RT12"
STATUS"NOPOP"
VALUE"3D01R5F-GP";
"2"
$PN"2"33;
"1"
$PN"1"19;
%"CAP_A"
"1","(-3850,775)","0","dev_discrete","I87";
;
CDS_SEC"1"
$SEC"1"
CDS_LOCATION"CT21"
ROOM"PVCCIN_CPU0_PWR_VR"
CDS_LIB"dev_discrete"
STATUS"NOPOP"
VOLTAGE"16V"
VALUE"0.1UF"
LOCATION"CT21"
PACK_TYPE"0402V"
PART_NUMBER"A36096-030"
MATERIAL"X7R"
TOLERANCE"10%";
"B"
$PN"2"20;
"A"
$PN"1"34;
%"GND"
"1","(-3850,525)","0","mstr_symbols","I88";
;
ROOM"PVCCIN_CPU0_PWR_VR"
BOM_COST"PROC_VRD_VCCIN_CPU0"
SIZE"1B"
VOLTAGE"0"
CDS_LIB"mstr_symbols"
BODY_TYPE"PLUMBING"
HDL_POWER"GND";
"A\NAC"20;
%"CAP_A"
"1","(-825,3425)","0","dev_discrete","I9";
;
CDS_LIB"dev_discrete"
CDS_LOCATION"C1D14"
ROOM"PVCCIN_CPU1_PWR_VR"
CDS_SEC"1"
BOM_COST"PROC_VRD_VCCIN_CPU0"
SEC"1"
SEC_TYPE"0603V"
MATERIAL"X6S"
VOLTAGE"4V"
VALUE"22.0UF"
PART_NUMBER"E15431-004"
LOCATION"C1D14"
TOLERANCE"20%"
PACK_TYPE"0603V";
"B"
$PN"2"1;
"A"
$PN"1"17;
%"CAP"
"1","(-2000,1300)","0","mstr_discrete","I90";
;
CDS_SEC"1"
$SEC"1"
CDS_LOCATION"CT19"
ROOM"VDDQ_KLM_PWR_VR"
CDS_LIB"mstr_discrete"
PACK_TYPE"0402LF"
MATERIAL"X7R"
VOLTAGE"50V"
VALUE"1000PF"
TOLERANCE"10%"
PART_NUMBER"A36096-046"
LOCATION"CT19"
STATUS"NOPOP";
"A"
$PN"1"31;
"B"
$PN"2"21;
%"GND"
"1","(-2000,1100)","0","mstr_symbols","I91";
;
SIZE"1B"
VOLTAGE"0"
ROOM"VDDQ_KLM_PWR_VR"
CDS_LIB"mstr_symbols"
BODY_TYPE"PLUMBING"
HDL_POWER"GND";
"A\NAC"21;
%"SC2K2P50V3KX-GP"
"1","(-1900,875)","0","w_hdl","I92";
;
CDS_SEC"1"
$SEC"1"
CDS_LOCATION"CT20"
PACK_TYPE"SMD-BCG6"
PART_NUMBER"78.22224.2BL"
CDS_LMAN_SYM_OUTLINE"-50,25,50,-25"
CDS_LIB"w_hdl"
VALUE"SC2K2P50V3KX-GP"
LOCATION"CT20"
STATUS"NOPOP";
"2"
$PN"2"32;
"1"
$PN"1"29;
%"GND"
"1","(-1900,400)","0","mstr_symbols","I93";
;
ROOM"PVCCIN_CPU0_PWR_VR"
BOM_COST"PROC_VRD_VCCIN_CPU0"
VOLTAGE"0"
SIZE"1B"
CDS_LIB"mstr_symbols"
BODY_TYPE"PLUMBING"
HDL_POWER"GND";
"A\NAC"22;
%"3D01R5F-GP"
"1","(-1900,650)","4","w_hdl","I94";
;
CDS_SEC"1"
$SEC"1"
CDS_LOCATION"RT13"
PACK_TYPE"SMD-RG5"
PART_NUMBER"64.3R015.16L"
CDS_LIB"w_hdl"
CDS_LMAN_SYM_OUTLINE"-50,75,50,-75"
LOCATION"RT13"
STATUS"NOPOP"
VALUE"3D01R5F-GP";
"2"
$PN"2"32;
"1"
$PN"1"22;
%"RES"
"1","(-4975,3700)","0","mstr_discrete","I96";
;
CDS_SEC"1"
$SEC"1"
CDS_LOCATION"RT11"
CDS_LIB"mstr_discrete"
ROOM"BMC_DEBUG_HEADER"
BOM_COST"DEBUG"
VALUE"0.0"
PACK_TYPE"0402"
MATERIAL"CHIP"
TOLERANCE"5%"
PART_NUMBER"G21497-005"
LOCATION"RT11"
WATTAGE"1/16W";
"B"
$PN"2"43;
"A"
$PN"1"41;
%"RES"
"1","(-4925,1075)","0","mstr_discrete","I97";
;
CDS_SEC"1"
$SEC"1"
CDS_LOCATION"RT14"
CDS_LIB"mstr_discrete"
ROOM"BMC_DEBUG_HEADER"
BOM_COST"DEBUG"
WATTAGE"1/16W"
VALUE"0.0"
LOCATION"RT14"
PART_NUMBER"G21497-005"
TOLERANCE"5%"
MATERIAL"CHIP"
PACK_TYPE"0402";
"B"
$PN"2"37;
"A"
$PN"1"36;
END.
